# TIMECARD (Time Appliance Project (Time Card)) — schematic netlist excerpt (pin names and nets, part order shuffled) for the footprints in the layout excerpt that follows; sources: Cadence DE-HDL packaged netlist, KiCad conversion of R4006-B0001-02_R01.brd

R178  RESISTOR  4.7KOHM 1%  pkg SMC_0402R_H016  page 30 : \1\ = XP3R3V ; \2\ = XP1R2V_PG_R

(kicad_pcb
	(version 20260206)
	(generator "pcbnew")
	(generator_version "10.0")
	(general
		(thickness 1.6)
		(legacy_teardrops no)
	)
	(paper "A4")
	(title_block
		(title "timecard-production-celestica-r4006 — R4006-B0001-02_R01.brd")
		(comment 1 "Time Appliance Project (Time Card) / footprints 266-266 of 1113")
	)
	(layers
		(0 "F.Cu" signal "TOP")
		(4 "In1.Cu" signal "L02_GND1")
		(6 "In2.Cu" signal "L03_SIG1")
		(8 "In3.Cu" signal "L04_GND2")
		(10 "In4.Cu" signal "L05_VCC1")
		(12 "In5.Cu" signal "L06_VCC2")
		(14 "In6.Cu" signal "L07_GND3")
		(16 "In7.Cu" signal "L08_SIG2")
		(18 "In8.Cu" signal "L09_GND4")
		(2 "B.Cu" signal "BOTTOM")
		(9 "F.Adhes" user "F.Adhesive")
		(11 "B.Adhes" user "B.Adhesive")
		(13 "F.Paste" user "Package Geometry/Pastemask Top")
		(15 "B.Paste" user "Package Geometry/Pastemask Bottom")
		(5 "F.SilkS" user "Ref Des/Silkscreen Top")
		(7 "B.SilkS" user "Ref Des/Silkscreen Bottom")
		(1 "F.Mask" user "Board Geometry/Soldermask Top")
		(3 "B.Mask" user "Board Geometry/Soldermask Bottom")
		(17 "Dwgs.User" user "User.Drawings")
		(19 "Cmts.User" user "User.Comments")
		(21 "Eco1.User" user "User.Eco1")
		(23 "Eco2.User" user "User.Eco2")
		(25 "Edge.Cuts" user "Board Geometry/Outline")
		(27 "Margin" user)
		(31 "F.CrtYd" user "Package Geometry/Place Bound Top")
		(29 "B.CrtYd" user "Package Geometry/Place Bound Bottom")
		(35 "F.Fab" user "Ref Des/Assembly Top")
		(33 "B.Fab" user "Ref Des/Assembly Bottom")
	)
	(footprint ""
		(layer "F.Cu")
		(at 100.2538 -68.072 180)
		(property "Reference" "R178"
			(at -2.8702 0.08763 0)
			(unlocked yes)
			(layer "F.SilkS")
			(effects
				(font
					(size 0.7874 0.5842)
					(thickness 0.1524)
				)
			)
		)
		(property "Value" "VAL*"
			(at 0.02032 2.13233 180)
			(unlocked yes)
			(layer "F.Fab")
			(hide yes)
			(effects
				(font
					(size 0.7874 0.5842)
					(thickness 0.1524)
				)
			)
		)
		(property "Tolerance" "TOL*"
			(at 0.044704 3.05435 180)
			(unlocked yes)
			(layer "Cmts.User")
			(hide yes)
			(effects
				(font
					(size 0.7874 0.5842)
					(thickness 0.1524)
				)
			)
		)
		(property "User Part Number" "PARTNUM*"
			(at 0.02032 4.024884 180)
			(unlocked yes)
			(layer "Cmts.User")
			(hide yes)
			(effects
				(font
					(size 0.7874 0.5842)
					(thickness 0.1524)
				)
			)
		)
		(property "Device Type" "RESISTOR-G155-14701-01,4.7KOHMA"
			(at 0.008382 1.210564 180)
			(unlocked yes)
			(layer "F.Fab")
			(hide yes)
			(effects
				(font
					(size 0.7874 0.5842)
					(thickness 0.1524)
				)
			)
		)
		(duplicate_pad_numbers_are_jumpers no)
		(fp_line
			(start 1.143 0.5588)
			(end 1.143 -0.5588)
			(stroke
				(width 0.1)
				(type default)
			)
			(layer "F.SilkS")
		)
		(fp_line
			(start 1.143 -0.5588)
			(end -1.143 -0.5588)
			(stroke
				(width 0.1)
				(type default)
			)
			(layer "F.SilkS")
		)
		(fp_line
			(start -1.143 0.5588)
			(end 1.143 0.5588)
			(stroke
				(width 0.1)
				(type default)
			)
			(layer "F.SilkS")
		)
		(fp_line
			(start -1.143 -0.5588)
			(end -1.143 0.5588)
			(stroke
				(width 0.1)
				(type default)
			)
			(layer "F.SilkS")
		)
		(fp_rect
			(start 1.143 -0.5588)
			(end -1.143 0.5588)
			(stroke
				(width 0)
				(type default)
			)
			(fill no)
			(layer "F.CrtYd")
		)
		(fp_line
			(start 0.508 0.3048)
			(end 0.508 -0.3048)
			(stroke
				(width 0.1)
				(type default)
			)
			(layer "F.Fab")
		)
		(fp_line
			(start 0.508 -0.3048)
			(end -0.508 -0.3048)
			(stroke
				(width 0.1)
				(type default)
			)
			(layer "F.Fab")
		)
		(fp_line
			(start -0.508 0.3048)
			(end 0.508 0.3048)
			(stroke
				(width 0.1)
				(type default)
			)
			(layer "F.Fab")
		)
		(fp_line
			(start -0.508 -0.3048)
			(end -0.508 0.3048)
			(stroke
				(width 0.1)
				(type default)
			)
			(layer "F.Fab")
		)
		(pad "1" smd rect
			(at -0.5334 0 180)
			(size 0.7112 0.6096)
			(layers "F.Cu" "F.Mask" "F.Paste")
			(net "XP3R3V")
		)
		(pad "2" smd rect
			(at 0.5334 0 180)
			(size 0.7112 0.6096)
			(layers "F.Cu" "F.Mask" "F.Paste")
			(net "XP1R2V_PG_R")
		)
		(zone
			(layer "F.Cu")
			(hatch none 0.5)
			(connect_pads
				(clearance 0)
			)
			(min_thickness 0.25)
			(keepout
				(tracks allowed)
				(vias not_allowed)
				(pads allowed)
				(copperpour not_allowed)
				(footprints allowed)
			)
			(placement
				(enabled no)
				(sheetname "")
			)
			(fill
				(thermal_gap 0.5)
				(thermal_bridge_width 0.5)
				(island_removal_mode 0)
			)
			(polygon
				(pts
					(xy 100.1776 -67.7672) (xy 100.33 -67.7672) (xy 100.33 -68.3768) (xy 100.1776 -68.3768)
				)
			)
		)
	)
)
